# T6G (Grand Teton) — schematic netlist excerpt (pin names and nets, part order shuffled) for the footprints in the layout excerpt that follows; sources: Cadence DE-HDL packaged netlist, KiCad conversion of 04192023_DAF0TMB3IC0_F0TG_MB_C_brd_V02_OCP.brd

R3185  Q_RES  33.2 1% CHIP  pkg 0402LF  page 139 : A = OCP_V3_2_WAKE_BUFF_N ; B = OCP_V3_2_WAKE_BUFF_R_N
R672  Q_RES  33.2 1% CHIP  pkg 0201LF  page 322 : A = SMB_RT_CPU1_P0_ROM_R_SCL ; B = SMB_RT_CPU1_P0_ROM_SCL
PC6901  Q_CAP  22UF 16V 20% X6S  pkg C0805  page 360 : A = SW_P12V_AUX_P1V8_RETIMER_CPU0_FLT ; B = GND

(kicad_pcb
	(version 20260206)
	(generator "pcbnew")
	(generator_version "10.0")
	(general
		(thickness 1.6)
		(legacy_teardrops no)
	)
	(paper "A4")
	(title_block
		(title "04192023_DAF0TMB3IC0_F0TG_MB_C_brd_V02_OCP.brd")
		(comment 1 "Grand Teton / footprints 3656-3658 of 8354")
	)
	(layers
		(0 "F.Cu" signal "TOP")
		(4 "In1.Cu" signal "GND")
		(6 "In2.Cu" signal "IN1")
		(8 "In3.Cu" signal "GND1")
		(10 "In4.Cu" signal "IN2")
		(12 "In5.Cu" signal "GND2")
		(14 "In6.Cu" signal "IN3")
		(16 "In7.Cu" signal "GND3")
		(18 "In8.Cu" signal "VCC")
		(20 "In9.Cu" signal "VCC1")
		(22 "In10.Cu" signal "GND4")
		(24 "In11.Cu" signal "IN4")
		(26 "In12.Cu" signal "GND5")
		(28 "In13.Cu" signal "IN5")
		(30 "In14.Cu" signal "GND6")
		(32 "In15.Cu" signal "IN6")
		(34 "In16.Cu" signal "GND7")
		(2 "B.Cu" signal "BOTTOM")
		(9 "F.Adhes" user "F.Adhesive")
		(11 "B.Adhes" user "B.Adhesive")
		(13 "F.Paste" user "Package Geometry/Pastemask Top")
		(15 "B.Paste" user "Package Geometry/Pastemask Bottom")
		(5 "F.SilkS" user "Ref Des/Silkscreen Top")
		(7 "B.SilkS" user "Ref Des/Silkscreen Bottom")
		(1 "F.Mask" user "Board Geometry/Soldermask Top")
		(3 "B.Mask" user "Board Geometry/Soldermask Bottom")
		(17 "Dwgs.User" user "User.Drawings")
		(19 "Cmts.User" user "User.Comments")
		(21 "Eco1.User" user "User.Eco1")
		(23 "Eco2.User" user "User.Eco2")
		(25 "Edge.Cuts" user "Board Geometry/Outline")
		(27 "Margin" user)
		(31 "F.CrtYd" user "Package Geometry/Place Bound Top")
		(29 "B.CrtYd" user "Package Geometry/Place Bound Bottom")
		(35 "F.Fab" user "Ref Des/Assembly Top")
		(33 "B.Fab" user "Ref Des/Assembly Bottom")
	)
	(footprint ""
		(layer "F.Cu")
		(at 103.5304 -396.6972 90)
		(property "Reference" "R672"
			(at 0 0 90)
			(layer "F.SilkS")
			(hide yes)
			(effects
				(font
					(size 1.27 1.27)
				)
			)
		)
		(property "Value" ""
			(at 0 0 90)
			(layer "F.Fab")
			(effects
				(font
					(size 1.27 1.27)
				)
			)
		)
		(duplicate_pad_numbers_are_jumpers no)
		(fp_line
			(start 0.32512 -0.175006)
			(end 0.32512 0.175006)
			(stroke
				(width 0.1)
				(type default)
			)
			(layer "F.Fab")
		)
		(fp_line
			(start -0.32512 -0.175006)
			(end 0.32512 -0.175006)
			(stroke
				(width 0.1)
				(type default)
			)
			(layer "F.Fab")
		)
		(fp_line
			(start 0.32512 0.175006)
			(end -0.32512 0.175006)
			(stroke
				(width 0.1)
				(type default)
			)
			(layer "F.Fab")
		)
		(fp_line
			(start -0.32512 0.175006)
			(end -0.32512 -0.175006)
			(stroke
				(width 0.1)
				(type default)
			)
			(layer "F.Fab")
		)
		(pad "1" smd rect
			(at -0.2667 0 90)
			(size 0.3048 0.381)
			(layers "F.Cu" "F.Mask" "F.Paste")
			(net "SMB_RT_CPU1_P0_ROM_R_SCL")
		)
		(pad "2" smd rect
			(at 0.2667 0 270)
			(size 0.3048 0.381)
			(layers "F.Cu" "F.Mask" "F.Paste")
			(net "SMB_RT_CPU1_P0_ROM_SCL")
		)
	)
	(footprint ""
		(layer "F.Cu")
		(at 244.2972 -287.376362)
		(property "Reference" "PC6901"
			(at 0 0 0)
			(layer "F.SilkS")
			(hide yes)
			(effects
				(font
					(size 1.27 1.27)
				)
			)
		)
		(property "Value" ""
			(at 0 0 0)
			(layer "F.Fab")
			(effects
				(font
					(size 1.27 1.27)
				)
			)
		)
		(duplicate_pad_numbers_are_jumpers no)
		(fp_line
			(start -1.524 -0.762)
			(end 1.524 -0.762)
			(stroke
				(width 0.1524)
				(type default)
			)
			(layer "F.SilkS")
		)
		(fp_line
			(start -1.524 0.762)
			(end -1.524 -0.762)
			(stroke
				(width 0.1524)
				(type default)
			)
			(layer "F.SilkS")
		)
		(fp_line
			(start 1.524 -0.762)
			(end 1.524 0.762)
			(stroke
				(width 0.1524)
				(type default)
			)
			(layer "F.SilkS")
		)
		(fp_line
			(start 1.524 0.762)
			(end -1.524 0.762)
			(stroke
				(width 0.1524)
				(type default)
			)
			(layer "F.SilkS")
		)
		(fp_line
			(start -1.1049 -0.724916)
			(end -1.1049 0.724916)
			(stroke
				(width 0.1)
				(type default)
			)
			(layer "F.Fab")
		)
		(fp_line
			(start -1.1049 0.724916)
			(end 1.1049 0.724916)
			(stroke
				(width 0.1)
				(type default)
			)
			(layer "F.Fab")
		)
		(fp_line
			(start 1.1049 -0.724916)
			(end -1.1049 -0.724916)
			(stroke
				(width 0.1)
				(type default)
			)
			(layer "F.Fab")
		)
		(fp_line
			(start 1.1049 0.724916)
			(end 1.1049 -0.724916)
			(stroke
				(width 0.1)
				(type default)
			)
			(layer "F.Fab")
		)
		(pad "1" smd rect
			(at -0.889 0 180)
			(size 1.016 1.27)
			(layers "F.Cu" "F.Mask" "F.Paste")
			(net "SW_P12V_AUX_P1V8_RETIMER_CPU0_FLT")
		)
		(pad "2" smd rect
			(at 0.889 0 180)
			(size 1.016 1.27)
			(layers "F.Cu" "F.Mask" "F.Paste")
			(net "GND")
		)
	)
	(footprint ""
		(layer "F.Cu")
		(at 94.605602 -41.445942 180)
		(property "Reference" "R3185"
			(at 0 0 180)
			(layer "F.SilkS")
			(hide yes)
			(effects
				(font
					(size 1.27 1.27)
				)
			)
		)
		(property "Value" ""
			(at 0 0 180)
			(layer "F.Fab")
			(effects
				(font
					(size 1.27 1.27)
				)
			)
		)
		(duplicate_pad_numbers_are_jumpers no)
		(fp_line
			(start 0.7874 0.4064)
			(end -0.7874 0.4064)
			(stroke
				(width 0.1524)
				(type default)
			)
			(layer "F.SilkS")
		)
		(fp_line
			(start 0.7874 -0.4064)
			(end 0.7874 0.4064)
			(stroke
				(width 0.1524)
				(type default)
			)
			(layer "F.SilkS")
		)
		(fp_line
			(start -0.7874 0.4064)
			(end -0.7874 -0.4064)
			(stroke
				(width 0.1524)
				(type default)
			)
			(layer "F.SilkS")
		)
		(fp_line
			(start -0.7874 -0.4064)
			(end 0.7874 -0.4064)
			(stroke
				(width 0.1524)
				(type default)
			)
			(layer "F.SilkS")
		)
		(fp_line
			(start 0.67945 0.3048)
			(end 0.120396 0.3048)
			(stroke
				(width 0.1)
				(type default)
			)
			(layer "F.Fab")
		)
		(fp_line
			(start 0.67945 -0.3048)
			(end 0.67945 0.3048)
			(stroke
				(width 0.1)
				(type default)
			)
			(layer "F.Fab")
		)
		(fp_line
			(start 0.12065 -0.2794)
			(end 0.12065 -0.3048)
			(stroke
				(width 0.1)
				(type default)
			)
			(layer "F.Fab")
		)
		(fp_line
			(start 0.12065 -0.3048)
			(end 0.67945 -0.3048)
			(stroke
				(width 0.1)
				(type default)
			)
			(layer "F.Fab")
		)
		(fp_line
			(start 0.120396 0.3048)
			(end 0.120396 0.2794)
			(stroke
				(width 0.1)
				(type default)
			)
			(layer "F.Fab")
		)
		(fp_line
			(start 0.120396 0.2794)
			(end -0.12065 0.2794)
			(stroke
				(width 0.1)
				(type default)
			)
			(layer "F.Fab")
		)
		(fp_line
			(start -0.12065 0.3048)
			(end -0.67945 0.3048)
			(stroke
				(width 0.1)
				(type default)
			)
			(layer "F.Fab")
		)
		(fp_line
			(start -0.12065 0.2794)
			(end -0.12065 0.3048)
			(stroke
				(width 0.1)
				(type default)
			)
			(layer "F.Fab")
		)
		(fp_line
			(start -0.12065 -0.2794)
			(end 0.12065 -0.2794)
			(stroke
				(width 0.1)
				(type default)
			)
			(layer "F.Fab")
		)
		(fp_line
			(start -0.12065 -0.305054)
			(end -0.12065 -0.2794)
			(stroke
				(width 0.1)
				(type default)
			)
			(layer "F.Fab")
		)
		(fp_line
			(start -0.67945 0.3048)
			(end -0.67945 -0.305054)
			(stroke
				(width 0.1)
				(type default)
			)
			(layer "F.Fab")
		)
		(fp_line
			(start -0.67945 -0.305054)
			(end -0.12065 -0.305054)
			(stroke
				(width 0.1)
				(type default)
			)
			(layer "F.Fab")
		)
		(pad "1" smd circle
			(at -0.40005 0 180)
			(size 0 0)
			(layers "F.Cu" "F.Mask" "F.Paste")
			(net "OCP_V3_2_WAKE_BUFF_N")
		)
		(pad "2" smd circle
			(at 0.40005 0 180)
			(size 0 0)
			(layers "F.Cu" "F.Mask" "F.Paste")
			(net "OCP_V3_2_WAKE_BUFF_R_N")
		)
	)
)
